#ISCELL
  pure_quanta quanta_title_block_c *
  *
#ISCELL
  pure_quanta_power cad_note *
  *
#CELL
  pure_quanta genoa_sp5 *
  page20_i159
#ISCELL
  mstr_standard offpage *
  page20_i160
#ISCELL
  mstr_standard offpage *
  page20_i161
#ISCELL
  mstr_standard tap *
  page20_i162
#ISCELL
  mstr_standard tap *
  page20_i163
#ISCELL
  mstr_standard tap *
  page20_i164
#ISCELL
  mstr_standard tap *
  page20_i165
#ISCELL
  mstr_standard tap *
  page20_i166
#ISCELL
  mstr_standard tap *
  page20_i167
#ISCELL
  mstr_standard tap *
  page20_i168
#ISCELL
  mstr_standard tap *
  page20_i169
#ISCELL
  mstr_standard tap *
  page20_i170
#ISCELL
  mstr_standard tap *
  page20_i171
#ISCELL
  mstr_standard tap *
  page20_i172
#ISCELL
  mstr_standard tap *
  page20_i173
#ISCELL
  mstr_standard tap *
  page20_i174
#ISCELL
  mstr_standard tap *
  page20_i175
#ISCELL
  mstr_standard tap *
  page20_i176
#ISCELL
  mstr_standard tap *
  page20_i177
#ISCELL
  mstr_standard tap *
  page20_i178
#ISCELL
  mstr_standard tap *
  page20_i179
#ISCELL
  mstr_standard tap *
  page20_i180
#ISCELL
  mstr_standard tap *
  page20_i181
#ISCELL
  mstr_standard tap *
  page20_i182
#ISCELL
  mstr_standard tap *
  page20_i183
#ISCELL
  mstr_standard tap *
  page20_i184
#ISCELL
  mstr_standard tap *
  page20_i185
#ISCELL
  mstr_standard tap *
  page20_i186
#ISCELL
  mstr_standard tap *
  page20_i187
#ISCELL
  mstr_standard tap *
  page20_i188
#ISCELL
  mstr_standard tap *
  page20_i189
#ISCELL
  mstr_standard tap *
  page20_i190
#ISCELL
  mstr_standard tap *
  page20_i191
#ISCELL
  mstr_standard tap *
  page20_i192
#ISCELL
  mstr_standard tap *
  page20_i193
#ISCELL
  mstr_standard tap *
  page20_i194
#ISCELL
  mstr_standard tap *
  page20_i195
#ISCELL
  mstr_standard offpage *
  page20_i196
#ISCELL
  mstr_standard tap *
  page20_i197
#ISCELL
  mstr_standard tap *
  page20_i198
#ISCELL
  mstr_standard tap *
  page20_i199
#ISCELL
  mstr_standard tap *
  page20_i200
#ISCELL
  mstr_standard tap *
  page20_i201
#ISCELL
  mstr_standard tap *
  page20_i202
#ISCELL
  mstr_standard tap *
  page20_i203
#ISCELL
  mstr_standard tap *
  page20_i204
#ISCELL
  mstr_standard tap *
  page20_i205
#ISCELL
  mstr_standard tap *
  page20_i206
#ISCELL
  mstr_standard tap *
  page20_i207
#ISCELL
  mstr_standard tap *
  page20_i208
#ISCELL
  mstr_standard tap *
  page20_i209
#ISCELL
  mstr_standard tap *
  page20_i210
#ISCELL
  mstr_standard tap *
  page20_i211
#ISCELL
  mstr_standard tap *
  page20_i212
#ISCELL
  mstr_standard tap *
  page20_i213
#ISCELL
  mstr_standard tap *
  page20_i214
#ISCELL
  mstr_standard tap *
  page20_i215
#ISCELL
  mstr_standard tap *
  page20_i216
#ISCELL
  mstr_standard tap *
  page20_i217
#ISCELL
  mstr_standard tap *
  page20_i218
#ISCELL
  mstr_standard tap *
  page20_i219
#ISCELL
  mstr_standard tap *
  page20_i220
#ISCELL
  mstr_standard tap *
  page20_i221
#ISCELL
  mstr_standard tap *
  page20_i222
#ISCELL
  mstr_standard tap *
  page20_i223
#ISCELL
  mstr_standard tap *
  page20_i224
#ISCELL
  mstr_standard tap *
  page20_i225
#ISCELL
  mstr_standard tap *
  page20_i226
#ISCELL
  mstr_standard tap *
  page20_i227
#ISCELL
  mstr_standard tap *
  page20_i228
#ISCELL
  mstr_standard tap *
  page20_i229
#ISCELL
  mstr_standard tap *
  page20_i230
#ISCELL
  mstr_standard tap *
  page20_i231
#ISCELL
  mstr_standard tap *
  page20_i232
#ISCELL
  mstr_standard tap *
  page20_i233
#ISCELL
  mstr_standard offpage *
  page20_i234
#ISCELL
  mstr_standard tap *
  page20_i235
#ISCELL
  mstr_standard tap *
  page20_i236
#ISCELL
  mstr_standard tap *
  page20_i237
#ISCELL
  mstr_standard tap *
  page20_i238
#ISCELL
  mstr_standard tap *
  page20_i239
#ISCELL
  mstr_standard tap *
  page20_i240
#ISCELL
  mstr_standard tap *
  page20_i241
#ISCELL
  mstr_standard tap *
  page20_i242
#ISCELL
  mstr_standard tap *
  page20_i243
#ISCELL
  mstr_standard tap *
  page20_i244
#ISCELL
  mstr_standard tap *
  page20_i245
#ISCELL
  mstr_standard tap *
  page20_i246
#ISCELL
  mstr_standard tap *
  page20_i247
#ISCELL
  mstr_standard tap *
  page20_i248
#ISCELL
  mstr_standard tap *
  page20_i249
#ISCELL
  mstr_standard tap *
  page20_i250
#ISCELL
  mstr_standard tap *
  page20_i251
#ISCELL
  mstr_standard tap *
  page20_i252
#ISCELL
  mstr_standard tap *
  page20_i253
#ISCELL
  mstr_standard tap *
  page20_i254
#ISCELL
  mstr_standard tap *
  page20_i255
#ISCELL
  mstr_standard tap *
  page20_i256
#ISCELL
  mstr_standard tap *
  page20_i257
#ISCELL
  mstr_standard tap *
  page20_i258
#ISCELL
  mstr_standard tap *
  page20_i259
#ISCELL
  mstr_standard tap *
  page20_i260
#ISCELL
  mstr_standard tap *
  page20_i261
#ISCELL
  mstr_standard tap *
  page20_i262
#ISCELL
  mstr_standard tap *
  page20_i263
#ISCELL
  mstr_standard tap *
  page20_i264
#ISCELL
  mstr_standard tap *
  page20_i265
#ISCELL
  mstr_standard tap *
  page20_i266
#ISCELL
  mstr_standard tap *
  page20_i267
#ISCELL
  mstr_standard tap *
  page20_i268
#ISCELL
  mstr_standard tap *
  page20_i269
#ISCELL
  mstr_standard tap *
  page20_i270
#ISCELL
  mstr_standard tap *
  page20_i271
#ISCELL
  mstr_standard tap *
  page20_i272
#ISCELL
  mstr_standard tap *
  page20_i273
#ISCELL
  mstr_standard tap *
  page20_i274
#ISCELL
  mstr_standard tap *
  page20_i275
#ISCELL
  mstr_standard tap *
  page20_i276
#ISCELL
  mstr_standard tap *
  page20_i277
#ISCELL
  mstr_standard tap *
  page20_i278
#ISCELL
  mstr_standard tap *
  page20_i279
#ISCELL
  mstr_standard tap *
  page20_i280
#ISCELL
  standard offpage *
  page20_i281
#ISCELL
  standard offpage *
  page20_i282
#ISCELL
  standard offpage *
  page20_i283
#ISCELL
  standard offpage *
  page20_i284
#ISCELL
  mstr_standard tap *
  page20_i285
#ISCELL
  mstr_standard tap *
  page20_i286
#ISCELL
  mstr_standard tap *
  page20_i287
#ISCELL
  mstr_standard tap *
  page20_i288
#ISCELL
  mstr_standard tap *
  page20_i289
#ISCELL
  mstr_standard tap *
  page20_i290
#ISCELL
  mstr_standard tap *
  page20_i291
#ISCELL
  mstr_standard tap *
  page20_i292
#ISCELL
  mstr_standard tap *
  page20_i293
#ISCELL
  mstr_standard tap *
  page20_i294
#ISCELL
  mstr_standard tap *
  page20_i295
#ISCELL
  mstr_standard tap *
  page20_i296
#ISCELL
  mstr_standard tap *
  page20_i297
#ISCELL
  mstr_standard tap *
  page20_i298
#ISCELL
  mstr_standard tap *
  page20_i299
#ISCELL
  mstr_standard tap *
  page20_i300
#ISCELL
  mstr_standard tap *
  page20_i301
#ISCELL
  standard offpage *
  page20_i302
#ISCELL
  standard offpage *
  page20_i303
#ISCELL
  standard offpage *
  page20_i304
#ISCELL
  standard offpage *
  page20_i305
#ISCELL
  standard offpage *
  page20_i306
#ISCELL
  standard offpage *
  page20_i307
#ISCELL
  standard offpage *
  page20_i308
#ISCELL
  mstr_standard offpage *
  page20_i309
#ISCELL
  standard offpage *
  page20_i310
#ISCELL
  standard offpage *
  page20_i311
#ISCELL
  standard offpage *
  page20_i312
#ISCELL
  standard offpage *
  page20_i313
#CELL
  pure_quanta q_res *
  page20_i314
#ISCELL
  mstr_standard offpage *
  page20_i315
#ISCELL
  standard offpage *
  page20_i316
